(kicad_pcb
	(version 20260206)
	(generator "pcbnew")
	(generator_version "10.0")
	(general
		(thickness 1.6)
		(legacy_teardrops no)
	)
	(paper "A4")
	(title_block
		(title "01162023_DA0F0TEBIF0_F0T_Expander_BD_F_brd_V02_OCP.brd")
		(comment 1 "Grand Teton / footprints 2917-2923 of 9728")
	)
	(layers
		(0 "F.Cu" signal "TOP")
		(4 "In1.Cu" signal "GND")
		(6 "In2.Cu" signal "VCC")
		(8 "In3.Cu" signal "VCC1")
		(10 "In4.Cu" signal "GND1")
		(12 "In5.Cu" signal "IN1")
		(14 "In6.Cu" signal "GND2")
		(16 "In7.Cu" signal "IN2")
		(18 "In8.Cu" signal "GND3")
		(20 "In9.Cu" signal "IN3")
		(22 "In10.Cu" signal "GND4")
		(24 "In11.Cu" signal "IN4")
		(26 "In12.Cu" signal "GND5")
		(28 "In13.Cu" signal "IN5")
		(30 "In14.Cu" signal "GND6")
		(32 "In15.Cu" signal "IN6")
		(34 "In16.Cu" signal "GND7")
		(2 "B.Cu" signal "BOTTOM")
		(9 "F.Adhes" user "F.Adhesive")
		(11 "B.Adhes" user "B.Adhesive")
		(13 "F.Paste" user "Package Geometry/Pastemask Top")
		(15 "B.Paste" user "Package Geometry/Pastemask Bottom")
		(5 "F.SilkS" user "Ref Des/Silkscreen Top")
		(7 "B.SilkS" user "Ref Des/Silkscreen Bottom")
		(1 "F.Mask" user "Board Geometry/Soldermask Top")
		(3 "B.Mask" user "Board Geometry/Soldermask Bottom")
		(17 "Dwgs.User" user "User.Drawings")
		(19 "Cmts.User" user "User.Comments")
		(21 "Eco1.User" user "User.Eco1")
		(23 "Eco2.User" user "User.Eco2")
		(25 "Edge.Cuts" user "Board Geometry/Outline")
		(27 "Margin" user)
		(31 "F.CrtYd" user "Package Geometry/Place Bound Top")
		(29 "B.CrtYd" user "Package Geometry/Place Bound Bottom")
		(35 "F.Fab" user "Ref Des/Assembly Top")
		(33 "B.Fab" user "Ref Des/Assembly Bottom")
	)
	(footprint ""
		(layer "F.Cu")
		(at 369.495578 -81.498694 180)
		(property "Reference" "R1602"
			(at 0 0 180)
			(layer "F.SilkS")
			(hide yes)
			(effects
				(font
					(size 1.27 1.27)
				)
			)
		)
		(property "Value" ""
			(at 0 0 180)
			(layer "F.Fab")
			(effects
				(font
					(size 1.27 1.27)
				)
			)
		)
		(duplicate_pad_numbers_are_jumpers no)
		(fp_line
			(start 0.7874 0.4064)
			(end -0.7874 0.4064)
			(stroke
				(width 0.1524)
				(type default)
			)
			(layer "F.SilkS")
		)
		(fp_line
			(start 0.7874 -0.4064)
			(end 0.7874 0.4064)
			(stroke
				(width 0.1524)
				(type default)
			)
			(layer "F.SilkS")
		)
		(fp_line
			(start -0.7874 0.4064)
			(end -0.7874 -0.4064)
			(stroke
				(width 0.1524)
				(type default)
			)
			(layer "F.SilkS")
		)
		(fp_line
			(start -0.7874 -0.4064)
			(end 0.7874 -0.4064)
			(stroke
				(width 0.1524)
				(type default)
			)
			(layer "F.SilkS")
		)
		(fp_line
			(start 0.67945 0.3048)
			(end 0.120396 0.3048)
			(stroke
				(width 0.1)
				(type default)
			)
			(layer "F.Fab")
		)
		(fp_line
			(start 0.67945 -0.3048)
			(end 0.67945 0.3048)
			(stroke
				(width 0.1)
				(type default)
			)
			(layer "F.Fab")
		)
		(fp_line
			(start 0.12065 -0.2794)
			(end 0.12065 -0.3048)
			(stroke
				(width 0.1)
				(type default)
			)
			(layer "F.Fab")
		)
		(fp_line
			(start 0.12065 -0.3048)
			(end 0.67945 -0.3048)
			(stroke
				(width 0.1)
				(type default)
			)
			(layer "F.Fab")
		)
		(fp_line
			(start 0.120396 0.3048)
			(end 0.120396 0.2794)
			(stroke
				(width 0.1)
				(type default)
			)
			(layer "F.Fab")
		)
		(fp_line
			(start 0.120396 0.2794)
			(end -0.12065 0.2794)
			(stroke
				(width 0.1)
				(type default)
			)
			(layer "F.Fab")
		)
		(fp_line
			(start -0.12065 0.3048)
			(end -0.67945 0.3048)
			(stroke
				(width 0.1)
				(type default)
			)
			(layer "F.Fab")
		)
		(fp_line
			(start -0.12065 0.2794)
			(end -0.12065 0.3048)
			(stroke
				(width 0.1)
				(type default)
			)
			(layer "F.Fab")
		)
		(fp_line
			(start -0.12065 -0.2794)
			(end 0.12065 -0.2794)
			(stroke
				(width 0.1)
				(type default)
			)
			(layer "F.Fab")
		)
		(fp_line
			(start -0.12065 -0.305054)
			(end -0.12065 -0.2794)
			(stroke
				(width 0.1)
				(type default)
			)
			(layer "F.Fab")
		)
		(fp_line
			(start -0.67945 0.3048)
			(end -0.67945 -0.305054)
			(stroke
				(width 0.1)
				(type default)
			)
			(layer "F.Fab")
		)
		(fp_line
			(start -0.67945 -0.305054)
			(end -0.12065 -0.305054)
			(stroke
				(width 0.1)
				(type default)
			)
			(layer "F.Fab")
		)
		(pad "1" smd circle
			(at -0.40005 0 180)
			(size 0 0)
			(layers "F.Cu" "F.Mask" "F.Paste")
			(net "P3V3_AUX")
		)
		(pad "2" smd circle
			(at 0.40005 0 180)
			(size 0 0)
			(layers "F.Cu" "F.Mask" "F.Paste")
			(net "SMB_BIC_I2C9_MUX1_SSD12_R_SDA")
		)
	)
	(footprint ""
		(layer "F.Cu")
		(at 211.506816 -368.007646)
		(property "Reference" "R492"
			(at 0 0 0)
			(layer "F.SilkS")
			(hide yes)
			(effects
				(font
					(size 1.27 1.27)
				)
			)
		)
		(property "Value" ""
			(at 0 0 0)
			(layer "F.Fab")
			(effects
				(font
					(size 1.27 1.27)
				)
			)
		)
		(duplicate_pad_numbers_are_jumpers no)
		(fp_line
			(start -0.7874 -0.4064)
			(end 0.7874 -0.4064)
			(stroke
				(width 0.1524)
				(type default)
			)
			(layer "F.SilkS")
		)
		(fp_line
			(start -0.7874 0.4064)
			(end -0.7874 -0.4064)
			(stroke
				(width 0.1524)
				(type default)
			)
			(layer "F.SilkS")
		)
		(fp_line
			(start 0.7874 -0.4064)
			(end 0.7874 0.4064)
			(stroke
				(width 0.1524)
				(type default)
			)
			(layer "F.SilkS")
		)
		(fp_line
			(start 0.7874 0.4064)
			(end -0.7874 0.4064)
			(stroke
				(width 0.1524)
				(type default)
			)
			(layer "F.SilkS")
		)
		(fp_line
			(start -0.67945 -0.305054)
			(end -0.12065 -0.305054)
			(stroke
				(width 0.1)
				(type default)
			)
			(layer "F.Fab")
		)
		(fp_line
			(start -0.67945 0.3048)
			(end -0.67945 -0.305054)
			(stroke
				(width 0.1)
				(type default)
			)
			(layer "F.Fab")
		)
		(fp_line
			(start -0.12065 -0.305054)
			(end -0.12065 -0.2794)
			(stroke
				(width 0.1)
				(type default)
			)
			(layer "F.Fab")
		)
		(fp_line
			(start -0.12065 -0.2794)
			(end 0.12065 -0.2794)
			(stroke
				(width 0.1)
				(type default)
			)
			(layer "F.Fab")
		)
		(fp_line
			(start -0.12065 0.2794)
			(end -0.12065 0.3048)
			(stroke
				(width 0.1)
				(type default)
			)
			(layer "F.Fab")
		)
		(fp_line
			(start -0.12065 0.3048)
			(end -0.67945 0.3048)
			(stroke
				(width 0.1)
				(type default)
			)
			(layer "F.Fab")
		)
		(fp_line
			(start 0.120396 0.2794)
			(end -0.12065 0.2794)
			(stroke
				(width 0.1)
				(type default)
			)
			(layer "F.Fab")
		)
		(fp_line
			(start 0.120396 0.3048)
			(end 0.120396 0.2794)
			(stroke
				(width 0.1)
				(type default)
			)
			(layer "F.Fab")
		)
		(fp_line
			(start 0.12065 -0.3048)
			(end 0.67945 -0.3048)
			(stroke
				(width 0.1)
				(type default)
			)
			(layer "F.Fab")
		)
		(fp_line
			(start 0.12065 -0.2794)
			(end 0.12065 -0.3048)
			(stroke
				(width 0.1)
				(type default)
			)
			(layer "F.Fab")
		)
		(fp_line
			(start 0.67945 -0.3048)
			(end 0.67945 0.3048)
			(stroke
				(width 0.1)
				(type default)
			)
			(layer "F.Fab")
		)
		(fp_line
			(start 0.67945 0.3048)
			(end 0.120396 0.3048)
			(stroke
				(width 0.1)
				(type default)
			)
			(layer "F.Fab")
		)
		(pad "1" smd circle
			(at -0.40005 0)
			(size 0 0)
			(layers "F.Cu" "F.Mask" "F.Paste")
			(net "HSC_FAULT_N")
		)
		(pad "2" smd circle
			(at 0.40005 0)
			(size 0 0)
			(layers "F.Cu" "F.Mask" "F.Paste")
			(net "FM_HSC_FAULT_N")
		)
	)
	(footprint ""
		(layer "F.Cu")
		(at 263.047734 -40.037258 90)
		(property "Reference" "U373"
			(at 0.501142 2.434336 90)
			(unlocked yes)
			(layer "F.SilkS")
			(effects
				(font
					(size 0.7874 0.5842)
					(thickness 0.1524)
				)
			)
		)
		(property "Value" ""
			(at 0 0 90)
			(layer "F.Fab")
			(effects
				(font
					(size 1.27 1.27)
				)
			)
		)
		(duplicate_pad_numbers_are_jumpers no)
		(fp_line
			(start -1.949958 -1.610106)
			(end 1.949958 -1.610106)
			(stroke
				(width 0.1524)
				(type default)
			)
			(layer "F.SilkS")
		)
		(fp_line
			(start 1.949958 -1.560068)
			(end 1.949958 1.610106)
			(stroke
				(width 0.1524)
				(type default)
			)
			(layer "F.SilkS")
		)
		(fp_line
			(start 1.949958 1.610106)
			(end -1.949958 1.610106)
			(stroke
				(width 0.1524)
				(type default)
			)
			(layer "F.SilkS")
		)
		(fp_line
			(start -1.949958 1.610106)
			(end -1.949958 -1.610106)
			(stroke
				(width 0.1524)
				(type default)
			)
			(layer "F.SilkS")
		)
		(fp_line
			(start 0.750062 -1.560068)
			(end 0.750062 1.560068)
			(stroke
				(width 0.1)
				(type default)
			)
			(layer "F.Fab")
		)
		(fp_line
			(start -0.750062 -1.560068)
			(end 0.750062 -1.560068)
			(stroke
				(width 0.1)
				(type default)
			)
			(layer "F.Fab")
		)
		(fp_line
			(start 0.750062 1.560068)
			(end -0.750062 1.560068)
			(stroke
				(width 0.1)
				(type default)
			)
			(layer "F.Fab")
		)
		(fp_line
			(start -0.750062 1.560068)
			(end -0.750062 -1.560068)
			(stroke
				(width 0.1)
				(type default)
			)
			(layer "F.Fab")
		)
		(pad "D" smd rect
			(at 1.100074 0)
			(size 1.016 1.4224)
			(layers "F.Cu" "F.Mask" "F.Paste")
			(net "SSD9_AUX_P3V3_EN")
		)
		(pad "G" smd rect
			(at -1.100074 -0.94996)
			(size 1.016 1.4224)
			(layers "F.Cu" "F.Mask" "F.Paste")
			(net "PRSNT_SSD9_R1_N")
		)
		(pad "S" smd rect
			(at -1.100074 0.94996)
			(size 1.016 1.4224)
			(layers "F.Cu" "F.Mask" "F.Paste")
			(net "GND")
		)
	)
	(footprint ""
		(layer "F.Cu")
		(at 80.782414 -29.875734)
		(property "Reference" "PU84"
			(at -3.011932 -1.76403 90)
			(unlocked yes)
			(layer "F.SilkS")
			(effects
				(font
					(size 0.7874 0.5842)
					(thickness 0.1524)
				)
			)
		)
		(property "Value" ""
			(at 0 0 0)
			(layer "F.Fab")
			(effects
				(font
					(size 1.27 1.27)
				)
			)
		)
		(duplicate_pad_numbers_are_jumpers no)
		(fp_line
			(start -1.239774 -1.495298)
			(end 1.239774 -1.495298)
			(stroke
				(width 0.1524)
				(type default)
			)
			(layer "F.SilkS")
		)
		(fp_line
			(start -1.239774 1.495298)
			(end -1.239774 -1.495298)
			(stroke
				(width 0.1524)
				(type default)
			)
			(layer "F.SilkS")
		)
		(fp_line
			(start 1.239774 -1.495298)
			(end 1.239774 1.495298)
			(stroke
				(width 0.1524)
				(type default)
			)
			(layer "F.SilkS")
		)
		(fp_line
			(start 1.239774 1.495298)
			(end -1.239774 1.495298)
			(stroke
				(width 0.1524)
				(type default)
			)
			(layer "F.SilkS")
		)
		(fp_poly
			(pts
				(xy -2.221738 -1.606042) (xy -2.94005 -0.887476) (xy -1.862328 -0.52832)
			)
			(stroke
				(width 0)
				(type default)
			)
			(fill yes)
			(layer "F.SilkS")
		)
		(fp_line
			(start -0.8001 -1.050036)
			(end 0.8001 -1.050036)
			(stroke
				(width 0.1)
				(type default)
			)
			(layer "F.Fab")
		)
		(fp_line
			(start -0.8001 1.050036)
			(end -0.8001 -1.050036)
			(stroke
				(width 0.1)
				(type default)
			)
			(layer "F.Fab")
		)
		(fp_line
			(start 0.8001 -1.050036)
			(end 0.8001 1.050036)
			(stroke
				(width 0.1)
				(type default)
			)
			(layer "F.Fab")
		)
		(fp_line
			(start 0.8001 1.050036)
			(end -0.8001 1.050036)
			(stroke
				(width 0.1)
				(type default)
			)
			(layer "F.Fab")
		)
		(fp_poly
			(pts
				(xy -2.458974 -0.508) (xy -2.458974 0.508) (xy -1.442974 0)
			)
			(stroke
				(width 0)
				(type default)
			)
			(fill yes)
			(layer "F.Fab")
		)
		(pad "1_2" smd circle
			(at -0.374904 0 90)
			(size 0 0)
			(layers "F.Cu" "F.Mask" "F.Paste")
			(net "P3V3_AUX")
		)
		(pad "3" smd rect
			(at -0.499872 0.999998)
			(size 0.254 0.7112)
			(layers "F.Cu" "F.Mask" "F.Paste")
			(net "GND")
		)
		(pad "4" smd rect
			(at 0 0.999998)
			(size 0.254 0.7112)
			(layers "F.Cu" "F.Mask" "F.Paste")
			(net "P3V3_SSD3_CO_ILIMIT")
		)
		(pad "5" smd rect
			(at 0.499872 0.999998)
			(size 0.254 0.7112)
			(layers "F.Cu" "F.Mask" "F.Paste")
			(net "P3V3_SSD3_CO_MODE")
		)
		(pad "6_7" smd circle
			(at 0.374904 0 270)
			(size 0 0)
			(layers "F.Cu" "F.Mask" "F.Paste")
			(net "P3V3_SSD3")
		)
		(pad "8" smd rect
			(at 0.499872 -0.999998)
			(size 0.254 0.7112)
			(layers "F.Cu" "F.Mask" "F.Paste")
			(net "P3V3_SSD3_CO_GATE")
		)
		(pad "9" smd rect
			(at 0 -0.999998)
			(size 0.254 0.7112)
			(layers "F.Cu" "F.Mask" "F.Paste")
			(net "P3V3_SSD3_CO_EN")
		)
		(pad "10" smd rect
			(at -0.499872 -0.999998)
			(size 0.254 0.7112)
			(layers "F.Cu" "F.Mask" "F.Paste")
			(net "P3V3_SSD3_CO_DV_DT")
		)
	)
	(footprint ""
		(layer "F.Cu")
		(at 207.523588 -216.886536 -90)
		(property "Reference" "U88"
			(at 1.138936 1.833118 90)
			(unlocked yes)
			(layer "F.SilkS")
			(effects
				(font
					(size 0.7874 0.5842)
					(thickness 0.1524)
				)
				(justify left)
			)
		)
		(property "Value" ""
			(at 0 0 270)
			(layer "F.Fab")
			(effects
				(font
					(size 1.27 1.27)
				)
			)
		)
		(duplicate_pad_numbers_are_jumpers no)
		(fp_line
			(start -0.8636 1.050036)
			(end 0.8636 1.050036)
			(stroke
				(width 0.1524)
				(type default)
			)
			(layer "F.SilkS")
		)
		(fp_line
			(start 0.8636 1.050036)
			(end 0.8636 -1.050036)
			(stroke
				(width 0.1524)
				(type default)
			)
			(layer "F.SilkS")
		)
		(fp_line
			(start 0 -0.508)
			(end -0.542036 -1.050036)
			(stroke
				(width 0.1524)
				(type default)
			)
			(layer "F.SilkS")
		)
		(fp_line
			(start -0.8636 -1.050036)
			(end -0.8636 1.050036)
			(stroke
				(width 0.1524)
				(type default)
			)
			(layer "F.SilkS")
		)
		(fp_line
			(start -0.542036 -1.050036)
			(end -0.8636 -1.050036)
			(stroke
				(width 0.1524)
				(type default)
			)
			(layer "F.SilkS")
		)
		(fp_line
			(start 0.542036 -1.050036)
			(end 0 -0.508)
			(stroke
				(width 0.1524)
				(type default)
			)
			(layer "F.SilkS")
		)
		(fp_line
			(start 0.8636 -1.050036)
			(end 0.542036 -1.050036)
			(stroke
				(width 0.1524)
				(type default)
			)
			(layer "F.SilkS")
		)
		(fp_poly
			(pts
				(xy -2.794 -1.258062) (xy -2.794 -0.242062) (xy -1.778 -0.750062)
			)
			(stroke
				(width 0)
				(type default)
			)
			(fill yes)
			(layer "F.SilkS")
		)
		(fp_line
			(start -1.199896 1.050036)
			(end 1.199896 1.050036)
			(stroke
				(width 0.1)
				(type default)
			)
			(layer "F.Fab")
		)
		(fp_line
			(start 1.199896 1.050036)
			(end 1.199896 -1.050036)
			(stroke
				(width 0.1)
				(type default)
			)
			(layer "F.Fab")
		)
		(fp_line
			(start -1.199896 -1.050036)
			(end -1.199896 1.050036)
			(stroke
				(width 0.1)
				(type default)
			)
			(layer "F.Fab")
		)
		(fp_line
			(start 1.199896 -1.050036)
			(end -1.199896 -1.050036)
			(stroke
				(width 0.1)
				(type default)
			)
			(layer "F.Fab")
		)
		(fp_poly
			(pts
				(xy -2.794 -1.258062) (xy -2.794 -0.242062) (xy -1.778 -0.750062)
			)
			(stroke
				(width 0)
				(type default)
			)
			(fill yes)
			(layer "F.Fab")
		)
		(pad "1" smd rect
			(at -1.35001 -0.750062 180)
			(size 0.2794 0.7112)
			(layers "F.Cu" "F.Mask" "F.Paste")
			(net "TP_FSA3357K8X_B2_RX")
		)
		(pad "2" smd rect
			(at -1.35001 -0.249936 180)
			(size 0.2794 0.7112)
			(layers "F.Cu" "F.Mask" "F.Paste")
			(net "UART_MB_BIC_RX_BUF_R")
		)
		(pad "3" smd rect
			(at -1.35001 0.249936 180)
			(size 0.2794 0.7112)
			(layers "F.Cu" "F.Mask" "F.Paste")
			(net "UART_FIO_DEBUG_R_RX")
		)
		(pad "4" smd rect
			(at -1.35001 0.750062 180)
			(size 0.2794 0.7112)
			(layers "F.Cu" "F.Mask" "F.Paste")
			(net "GND")
		)
		(pad "5" smd rect
			(at 1.35001 0.750062 180)
			(size 0.2794 0.7112)
			(layers "F.Cu" "F.Mask" "F.Paste")
			(net "BIC_UART_SEL2")
		)
		(pad "6" smd rect
			(at 1.35001 0.249936 180)
			(size 0.2794 0.7112)
			(layers "F.Cu" "F.Mask" "F.Paste")
			(net "BIC_UART_SEL1")
		)
		(pad "7" smd rect
			(at 1.35001 -0.249936 180)
			(size 0.2794 0.7112)
			(layers "F.Cu" "F.Mask" "F.Paste")
			(net "UART_BIC_DEBUG_RX")
		)
		(pad "8" smd rect
			(at 1.35001 -0.750062 180)
			(size 0.2794 0.7112)
			(layers "F.Cu" "F.Mask" "F.Paste")
			(net "P3V3_AUX")
		)
	)
	(footprint ""
		(layer "F.Cu")
		(at 344.612976 -83.255358 180)
		(property "Reference" "R1176"
			(at 0 0 180)
			(layer "F.SilkS")
			(hide yes)
			(effects
				(font
					(size 1.27 1.27)
				)
			)
		)
		(property "Value" ""
			(at 0 0 180)
			(layer "F.Fab")
			(effects
				(font
					(size 1.27 1.27)
				)
			)
		)
		(duplicate_pad_numbers_are_jumpers no)
		(fp_line
			(start -0.7874 -0.4064)
			(end 0.7874 -0.4064)
			(stroke
				(width 0.1524)
				(type default)
			)
			(layer "F.SilkS")
		)
		(fp_line
			(start 0.67945 0.3048)
			(end 0.120396 0.3048)
			(stroke
				(width 0.1)
				(type default)
			)
			(layer "F.Fab")
		)
		(fp_line
			(start 0.67945 -0.3048)
			(end 0.67945 0.3048)
			(stroke
				(width 0.1)
				(type default)
			)
			(layer "F.Fab")
		)
		(fp_line
			(start 0.12065 -0.2794)
			(end 0.12065 -0.3048)
			(stroke
				(width 0.1)
				(type default)
			)
			(layer "F.Fab")
		)
		(fp_line
			(start 0.12065 -0.3048)
			(end 0.67945 -0.3048)
			(stroke
				(width 0.1)
				(type default)
			)
			(layer "F.Fab")
		)
		(fp_line
			(start 0.120396 0.3048)
			(end 0.120396 0.2794)
			(stroke
				(width 0.1)
				(type default)
			)
			(layer "F.Fab")
		)
		(fp_line
			(start 0.120396 0.2794)
			(end -0.12065 0.2794)
			(stroke
				(width 0.1)
				(type default)
			)
			(layer "F.Fab")
		)
		(fp_line
			(start -0.12065 0.3048)
			(end -0.67945 0.3048)
			(stroke
				(width 0.1)
				(type default)
			)
			(layer "F.Fab")
		)
		(fp_line
			(start -0.12065 0.2794)
			(end -0.12065 0.3048)
			(stroke
				(width 0.1)
				(type default)
			)
			(layer "F.Fab")
		)
		(fp_line
			(start -0.12065 -0.2794)
			(end 0.12065 -0.2794)
			(stroke
				(width 0.1)
				(type default)
			)
			(layer "F.Fab")
		)
		(fp_line
			(start -0.12065 -0.305054)
			(end -0.12065 -0.2794)
			(stroke
				(width 0.1)
				(type default)
			)
			(layer "F.Fab")
		)
		(fp_line
			(start -0.67945 0.3048)
			(end -0.67945 -0.305054)
			(stroke
				(width 0.1)
				(type default)
			)
			(layer "F.Fab")
		)
		(fp_line
			(start -0.67945 -0.305054)
			(end -0.12065 -0.305054)
			(stroke
				(width 0.1)
				(type default)
			)
			(layer "F.Fab")
		)
		(pad "1" smd circle
			(at -0.40005 0 180)
			(size 0 0)
			(layers "F.Cu" "F.Mask" "F.Paste")
			(net "CLK_100M_DB800ZL_SSD11_R_DP")
		)
		(pad "2" smd circle
			(at 0.40005 0 180)
			(size 0 0)
			(layers "F.Cu" "F.Mask" "F.Paste")
			(net "CLK_100M_DB800ZL_SSD11_DP")
		)
	)
	(footprint ""
		(layer "F.Cu")
		(at 137.622788 -343.952322 90)
		(property "Reference" "C2252"
			(at 0 0 90)
			(layer "F.SilkS")
			(hide yes)
			(effects
				(font
					(size 1.27 1.27)
				)
			)
		)
		(property "Value" ""
			(at 0 0 90)
			(layer "F.Fab")
			(effects
				(font
					(size 1.27 1.27)
				)
			)
		)
		(duplicate_pad_numbers_are_jumpers no)
		(fp_line
			(start 0.299974 -0.150114)
			(end 0.299974 0.150114)
			(stroke
				(width 0.1)
				(type default)
			)
			(layer "F.Fab")
		)
		(fp_line
			(start -0.299974 -0.150114)
			(end 0.299974 -0.150114)
			(stroke
				(width 0.1)
				(type default)
			)
			(layer "F.Fab")
		)
		(fp_line
			(start 0.299974 0.150114)
			(end -0.299974 0.150114)
			(stroke
				(width 0.1)
				(type default)
			)
			(layer "F.Fab")
		)
		(fp_line
			(start -0.299974 0.150114)
			(end -0.299974 -0.150114)
			(stroke
				(width 0.1)
				(type default)
			)
			(layer "F.Fab")
		)
		(pad "1" smd rect
			(at -0.2667 0 90)
			(size 0.3048 0.381)
			(layers "F.Cu" "F.Mask" "F.Paste")
			(net "P5E_PEX1_STN5_TX_DN<91>")
		)
		(pad "2" smd rect
			(at 0.2667 0 90)
			(size 0.3048 0.381)
			(layers "F.Cu" "F.Mask" "F.Paste")
			(net "P5E_PEX1_STN5_TX_C_DN<91>")
		)
	)
)
